# S9S_MB_2U (Grand Teton) — schematic netlist excerpt (pin names and nets, part order shuffled) for the footprints in the layout excerpt that follows; sources: Cadence DE-HDL packaged netlist, KiCad conversion of 03242023_DA0F0TMBIJ0_F0T_Motherboard_J_brd_V01_OCP.brd

Q131  MOSFET_NCH_DUAL  PJT138K IC  pkg SOT363XD  page 146
  S1  = GND
  G1  = GPU_3V3IO_RSVD1_FFU
  D2  = GPU_3V3IO_RSVD1_FFU_ISO
  S2  = GND
  G2  = GPU_3V3IO_RSVD1_FFU_N
  D1  = GPU_3V3IO_RSVD1_FFU_N

R4487  Q_RES  49.9 1% EMPTY  pkg 0402LF  page 196 : A = USB2_HOST_PCH_0_DN ; B = GND

(kicad_pcb
	(version 20260206)
	(generator "pcbnew")
	(generator_version "10.0")
	(general
		(thickness 1.6)
		(legacy_teardrops no)
	)
	(paper "A4")
	(title_block
		(title "03242023_DA0F0TMBIJ0_F0T_Motherboard_J_brd_V01_OCP.brd")
		(comment 1 "Grand Teton / footprints 2829-2830 of 6105")
	)
	(layers
		(0 "F.Cu" signal "TOP")
		(4 "In1.Cu" signal "GND")
		(6 "In2.Cu" signal "IN1")
		(8 "In3.Cu" signal "GND1")
		(10 "In4.Cu" signal "IN2")
		(12 "In5.Cu" signal "GND2")
		(14 "In6.Cu" signal "IN3")
		(16 "In7.Cu" signal "GND3")
		(18 "In8.Cu" signal "VCC")
		(20 "In9.Cu" signal "VCC1")
		(22 "In10.Cu" signal "GND4")
		(24 "In11.Cu" signal "IN4")
		(26 "In12.Cu" signal "GND5")
		(28 "In13.Cu" signal "IN5")
		(30 "In14.Cu" signal "GND6")
		(32 "In15.Cu" signal "IN6")
		(34 "In16.Cu" signal "GND7")
		(2 "B.Cu" signal "BOTTOM")
		(9 "F.Adhes" user "F.Adhesive")
		(11 "B.Adhes" user "B.Adhesive")
		(13 "F.Paste" user "Package Geometry/Pastemask Top")
		(15 "B.Paste" user "Package Geometry/Pastemask Bottom")
		(5 "F.SilkS" user "Ref Des/Silkscreen Top")
		(7 "B.SilkS" user "Ref Des/Silkscreen Bottom")
		(1 "F.Mask" user "Board Geometry/Soldermask Top")
		(3 "B.Mask" user "Board Geometry/Soldermask Bottom")
		(17 "Dwgs.User" user "User.Drawings")
		(19 "Cmts.User" user "User.Comments")
		(21 "Eco1.User" user "User.Eco1")
		(23 "Eco2.User" user "User.Eco2")
		(25 "Edge.Cuts" user "Board Geometry/Outline")
		(27 "Margin" user)
		(31 "F.CrtYd" user "Package Geometry/Place Bound Top")
		(29 "B.CrtYd" user "Package Geometry/Place Bound Bottom")
		(35 "F.Fab" user "Ref Des/Assembly Top")
		(33 "B.Fab" user "Ref Des/Assembly Bottom")
	)
	(footprint ""
		(layer "F.Cu")
		(at 308.66334 -435.71541 90)
		(property "Reference" "Q131"
			(at 4.467098 -1.20269 0)
			(unlocked yes)
			(layer "F.SilkS")
			(effects
				(font
					(size 0.7874 0.5842)
					(thickness 0.1524)
				)
				(justify left)
			)
		)
		(property "Value" ""
			(at 0 0 90)
			(layer "F.Fab")
			(effects
				(font
					(size 1.27 1.27)
				)
			)
		)
		(duplicate_pad_numbers_are_jumpers no)
		(fp_line
			(start 1.332738 -1.100074)
			(end 1.332738 1.100074)
			(stroke
				(width 0.1524)
				(type default)
			)
			(layer "F.SilkS")
		)
		(fp_line
			(start 0.4826 -1.100074)
			(end 1.332738 -1.100074)
			(stroke
				(width 0.1524)
				(type default)
			)
			(layer "F.SilkS")
		)
		(fp_line
			(start -0.4826 -1.100074)
			(end 0 -0.541274)
			(stroke
				(width 0.1524)
				(type default)
			)
			(layer "F.SilkS")
		)
		(fp_line
			(start -1.332738 -1.100074)
			(end -0.4826 -1.100074)
			(stroke
				(width 0.1524)
				(type default)
			)
			(layer "F.SilkS")
		)
		(fp_line
			(start 0 -0.541274)
			(end 0.4826 -1.100074)
			(stroke
				(width 0.1524)
				(type default)
			)
			(layer "F.SilkS")
		)
		(fp_line
			(start 1.332738 1.100074)
			(end -1.332738 1.100074)
			(stroke
				(width 0.1524)
				(type default)
			)
			(layer "F.SilkS")
		)
		(fp_line
			(start -1.332738 1.100074)
			(end -1.332738 -1.100074)
			(stroke
				(width 0.1524)
				(type default)
			)
			(layer "F.SilkS")
		)
		(fp_poly
			(pts
				(xy -2.43586 -1.303274) (xy -1.733804 -0.952246) (xy -2.43586 -0.601218)
			)
			(stroke
				(width 0)
				(type default)
			)
			(fill yes)
			(layer "F.SilkS")
		)
		(fp_line
			(start 0.674878 -1.100074)
			(end 0.674878 1.100074)
			(stroke
				(width 0.1)
				(type default)
			)
			(layer "F.Fab")
		)
		(fp_line
			(start -0.674878 -1.100074)
			(end 0.674878 -1.100074)
			(stroke
				(width 0.1)
				(type default)
			)
			(layer "F.Fab")
		)
		(fp_line
			(start 0.674878 1.100074)
			(end -0.674878 1.100074)
			(stroke
				(width 0.1)
				(type default)
			)
			(layer "F.Fab")
		)
		(fp_line
			(start -0.674878 1.100074)
			(end -0.674878 -1.100074)
			(stroke
				(width 0.1)
				(type default)
			)
			(layer "F.Fab")
		)
		(fp_poly
			(pts
				(xy -2.2352 -0.298958) (xy -2.2352 -1.001014) (xy -1.533144 -0.649986)
			)
			(stroke
				(width 0)
				(type default)
			)
			(fill yes)
			(layer "F.Fab")
		)
		(pad "1" smd rect
			(at -0.94996 -0.649986 180)
			(size 0.4318 0.508)
			(layers "F.Cu" "F.Mask" "F.Paste")
			(net "GND")
		)
		(pad "2" smd rect
			(at -0.94996 0 180)
			(size 0.4318 0.508)
			(layers "F.Cu" "F.Mask" "F.Paste")
			(net "GPU_3V3IO_RSVD1_FFU")
		)
		(pad "3" smd rect
			(at -0.94996 0.649986 180)
			(size 0.4318 0.508)
			(layers "F.Cu" "F.Mask" "F.Paste")
			(net "GPU_3V3IO_RSVD1_FFU_ISO")
		)
		(pad "4" smd rect
			(at 0.94996 0.649986 180)
			(size 0.4318 0.508)
			(layers "F.Cu" "F.Mask" "F.Paste")
			(net "GND")
		)
		(pad "5" smd rect
			(at 0.94996 0 180)
			(size 0.4318 0.508)
			(layers "F.Cu" "F.Mask" "F.Paste")
			(net "GPU_3V3IO_RSVD1_FFU_N")
		)
		(pad "6" smd rect
			(at 0.94996 -0.649986 180)
			(size 0.4318 0.508)
			(layers "F.Cu" "F.Mask" "F.Paste")
			(net "GPU_3V3IO_RSVD1_FFU_N")
		)
	)
	(footprint ""
		(layer "F.Cu")
		(at 157.430978 -46.741588)
		(property "Reference" "R4487"
			(at 0 0 0)
			(layer "F.SilkS")
			(hide yes)
			(effects
				(font
					(size 1.27 1.27)
				)
			)
		)
		(property "Value" ""
			(at 0 0 0)
			(layer "F.Fab")
			(effects
				(font
					(size 1.27 1.27)
				)
			)
		)
		(duplicate_pad_numbers_are_jumpers no)
		(fp_line
			(start -0.009398 -0.4064)
			(end 0.7874 -0.4064)
			(stroke
				(width 0.1524)
				(type default)
			)
			(layer "F.SilkS")
		)
		(fp_line
			(start 0.7874 -0.4064)
			(end 0.7874 0.4064)
			(stroke
				(width 0.1524)
				(type default)
			)
			(layer "F.SilkS")
		)
		(fp_line
			(start 0.7874 0.4064)
			(end 0.041402 0.4064)
			(stroke
				(width 0.1524)
				(type default)
			)
			(layer "F.SilkS")
		)
		(fp_line
			(start -0.67945 -0.305054)
			(end -0.12065 -0.305054)
			(stroke
				(width 0.1)
				(type default)
			)
			(layer "F.Fab")
		)
		(fp_line
			(start -0.67945 0.3048)
			(end -0.67945 -0.305054)
			(stroke
				(width 0.1)
				(type default)
			)
			(layer "F.Fab")
		)
		(fp_line
			(start -0.12065 -0.305054)
			(end -0.12065 -0.2794)
			(stroke
				(width 0.1)
				(type default)
			)
			(layer "F.Fab")
		)
		(fp_line
			(start -0.12065 -0.2794)
			(end 0.12065 -0.2794)
			(stroke
				(width 0.1)
				(type default)
			)
			(layer "F.Fab")
		)
		(fp_line
			(start -0.12065 0.2794)
			(end -0.12065 0.3048)
			(stroke
				(width 0.1)
				(type default)
			)
			(layer "F.Fab")
		)
		(fp_line
			(start -0.12065 0.3048)
			(end -0.67945 0.3048)
			(stroke
				(width 0.1)
				(type default)
			)
			(layer "F.Fab")
		)
		(fp_line
			(start 0.120396 0.2794)
			(end -0.12065 0.2794)
			(stroke
				(width 0.1)
				(type default)
			)
			(layer "F.Fab")
		)
		(fp_line
			(start 0.120396 0.3048)
			(end 0.120396 0.2794)
			(stroke
				(width 0.1)
				(type default)
			)
			(layer "F.Fab")
		)
		(fp_line
			(start 0.12065 -0.3048)
			(end 0.67945 -0.3048)
			(stroke
				(width 0.1)
				(type default)
			)
			(layer "F.Fab")
		)
		(fp_line
			(start 0.12065 -0.2794)
			(end 0.12065 -0.3048)
			(stroke
				(width 0.1)
				(type default)
			)
			(layer "F.Fab")
		)
		(fp_line
			(start 0.67945 -0.3048)
			(end 0.67945 0.3048)
			(stroke
				(width 0.1)
				(type default)
			)
			(layer "F.Fab")
		)
		(fp_line
			(start 0.67945 0.3048)
			(end 0.120396 0.3048)
			(stroke
				(width 0.1)
				(type default)
			)
			(layer "F.Fab")
		)
		(pad "1" smd circle
			(at -0.40005 0)
			(size 0 0)
			(layers "F.Cu" "F.Mask" "F.Paste")
			(net "USB2_HOST_PCH_0_DN")
		)
		(pad "2" smd circle
			(at 0.40005 0)
			(size 0 0)
			(layers "F.Cu" "F.Mask" "F.Paste")
			(net "GND")
		)
	)
)
